# Barreleye-G2_Tri-mode BPX24-DVT-X01-SKU-BOM-X07-20171222_Final.xls.xlsx — SKU2 (bom)
| FOXCONN TECHNOLOGY GROUP |  |  |  |  |  |  |  |  |  |  |  |  |  |  |  |  |  |  |  |
| BILL OF MATERIAL |  |  |  |  |  |  |  |  |  |  |  |  |  |  |  |  |  |  |  |
| REV OF  BOM |  | CUSTOMER |  | <name> |  | CUSTOMER P/N |  | AA P/N：1A42NC500-600-2 | PWA DESCRIPTION |  |  |  | PRODUCT CODE |  |  | PWA  REV |  | DATE |  |
| Sourcing (Single/Sole/Multi) | Critical Commodity (Y or N) | Component Class (1, 2, other) | Customer PSL (Y or N) | Line Item | Item Number | Foxconn P/N | Customer P/N | Part Description | Manufacturer  Full Name | Manufacturer  Part Number | Qty | RoHS Status | Location | CC Qual Build: | Qual by (Customer / ODM ?) | The Date of Change Part or Add 2nd Source | Configuration Identifier | Customer Comments | ODM Comments |
|  |  |  |  | 1 | 1 | 0101FGA00-000-G |  | PCB,Zaius-Tri-mode BPX24 DVT-X01,OSP,Blu,22L,21.122*3.470,G | GOLD CIRCUIT ELECTRONICS LTD. | 0101FGA00-000-G | 1 | G | PCB |  |  |  |  |  |  |
|  |  |  |  |  | 1 | 0101FGA00-000-G |  | PCB,Zaius-Tri-mode BPX24 DVT-X01,OSP,Blu,22L,21.122*3.470,G | ZHUHAI FOUNDER PRINTED CIRCUIT BOARD（HK） DEVELOPMENT LIMITED | 0101FGA00-000-G |  | G |  |  |  |  |  |  |  |
|  |  |  |  | 2 | 2 | 62110EH00-024-G |  | ECAP,680uF,+/-20%,16V,105_x0003_,G,SMD10X10.2,ESR<=80mOhm | PANASONIC INDUSTRIAL CO.,LTD. | EEEFK1C681P | 1 | G | CE1 |  |  |  |  |  |  |
|  |  |  |  | 3 | 3 | 620101T02-015-G | - | CAP,100nF,+/-10%,X7R,16V,G,SMD0402 | MURATA ELEC. NORTH AMERICA | GRM155R71C104K | 145 | G | PSTC1,PFTC1,PETC1,C1,C2,C6,C8,C9,PSRC10,C10,C15,C19,C119,C123,C125,C129,C155,C159,C161,C165,C167,C171,C173,C177,C179,C183,C185,C189,C191,C192,C193,C194,C196,C198,C201,C207,C216,C217,C224,C249,C253,C255,C259,C261,C265,C267,C271,C273,C277,C279,C283,C285,C289,C291,C295,C297,C301,C303,C307,C309,C313,C315,C319,C321,C325,C327,C331,C333,C337,C339,C343,C397,C2101,C2102,C2103,C2104,C2105,C2106,C2107,C2108,C2109,C2110,C2111,C2112,C2113,C2114,C2115,C2116,C2117,C2118,C2119,C2120,C2121,C2122,C2123,C2124,C2125,C2126,C2127,C2128,C2129,C2130,C2131,C2132,C2133,C2134,C2135,C2136,C2137,C2138,C2139,C2140,C2141,C2143,C2145,C2147,C2149,C2169,C2171,C2176,C2177,C2178,C2232,C2233,C2234,C2235,C2237,C2239,C2240,C2241,C2242,C2254,C2255,C2256,C2259,C2260,C2261,C2262,C2263,C2264,C2265,C2266,C2270,C2271,C2272 |  |  |  |  |  |  |
|  |  |  |  |  | 3 | 620101T00-012-G |  | CAP,100nF,+/-10%,X7R,16V,G,SMD0402 | WALSIN TECHNOLOGY CORPORATION | 0402B104K160CT |  | G |  |  |  |  |  |  |  |
|  |  |  |  |  | 3 | 620101T00-026-G |  | CAP,100nF,+/-10%,X7R,16V,G,SMD0402 | SAMSUNG SEMICONDUCTOR | CL05B104KO5NNNC |  | G |  |  |  |  |  |  |  |
|  |  |  |  |  | 3 | 620101T00-015-G |  | CAP,100nF,+/-10%,X7R,16V,G,SMD0402 | MURATA ELEC. NORTH AMERICA | GRM155R71C104KA88D |  | G |  |  |  |  |  |  |  |
|  |  |  |  | 4 | 4 | 620100A00-015-G | - | CAP,10uF,+/-10%,X5R,16V,G,SMD1206 | MURATA ELEC. NORTH AMERICA | GRM31CR61C106K | 30 | G | C3,C4,C5,C7,C120,C128,C158,C164,C170,C176,C182,C188,C252,C258,C264,C270,C276,C282,C288,C294,C300,C306,C312,C318,C324,C330,C336,C342,C2236,C2238 |  |  |  |  |  |  |
|  |  |  |  |  | 4 | 620100A00-026-G |  | CAP,10uF,+/-10%,X5R,16V,G,SMD1206 | SAMSUNG SEMICONDUCTOR | CL31A106KOHNNNE |  | G |  |  |  |  |  |  |  |
|  |  |  |  |  | 4 | 620100A03-023-G |  | CAP,10uF,+/-10%,X5R,16V,G,SMD1206 | TAIYO ELECTRIC IND.CO.LTD | EMK316BJ106KL-T |  | G |  |  |  |  |  |  |  |
|  |  |  |  |  | 4 | 620100A00-012-G |  | CAP,10uF,+/-10%,X5R,16V,G,SMD1206 | WALSIN TECHNOLOGY CORPORATION | 1206X106K160CT |  | G |  |  |  |  |  |  |  |
|  |  |  |  |  | 4 | 620100A00-011-G |  | CAP,10uF,+/-10%,X5R,16V,G,SMD1206 | YAGEO CORPORATION COMPONENT | CC1206KKX5R7BB106 |  | G |  |  |  |  |  |  |  |
|  |  |  |  | 5 | 5 | 620117N00-015-G | - | CAP,22uF,+/-10%,X5R,16V,G,SMD1206 | MURATA ELEC. NORTH AMERICA | GRM31CR61C226K | 48 | G | C121,C122,C126,C130,C156,C160,C162,C166,C168,C172,C174,C178,C180,C184,C186,C190,C250,C254,C256,C260,C262,C266,C268,C272,C274,C278,C280,C284,C286,C290,C292,C296,C298,C302,C304,C308,C310,C314,C316,C320,C322,C326,C328,C332,C334,C338,C340,C344 |  |  |  |  |  |  |
|  |  |  |  |  | 5 | 620117N00-023-G |  | CAP,22uF,+/-10%,X5R,16V,G,SMD1206 | TAIYO ELECTRIC IND.CO.LTD | EMK316BJ226KL-T |  | G |  |  |  |  |  |  |  |
|  |  |  |  |  | 5 | 620117N01-026-G |  | CAP,22uF,+/-10%,X5R,16V,G,SMD1206 | SAMSUNG SEMICONDUCTOR | CL31A226KOHNNNE |  | G |  |  |  |  |  |  |  |
|  |  |  |  | 6 | 6 | 620108H00-015-G | - | CAP,22uF,+/-20%,X5R,6.3V,G,SMD0805 | MURATA ELEC. NORTH AMERICA | GRM21BR60J226M | 24 | G | C124,C127,C157,C163,C169,C175,C181,C187,C251,C257,C263,C269,C275,C281,C287,C293,C299,C305,C311,C317,C323,C329,C335,C341 |  |  |  |  |  |  |
|  |  |  |  |  | 6 | 620108H04-023-G |  | CAP,22uF,+/-20%,X5R,6.3V,G,SMD0805 | TAIYO ELECTRIC IND.CO.LTD | JMK212BJ226MG-T |  | G |  |  |  |  |  |  |  |
|  |  |  |  |  | 6 | 620108H00-026-G |  | CAP,22uF,+/-20%,X5R,6.3V,G,SMD0805 | SAMSUNG SEMICONDUCTOR | CL21A226MQQNNNE |  | G |  |  |  |  |  |  |  |
|  |  |  |  |  | 6 | 620108H00-011-G |  | CAP,22uF,+/-20%,X5R,6.3V,G,SMD0805 | YAGEO CORPORATION COMPONENT | CC0805MKX5R5BB226 |  | G |  |  |  |  |  |  |  |
|  |  |  |  | 7 | 7 | 62011AM00-015-G |  | CAP,6.8nF,+/-10%,X7R,50V,G,SMD0402 | MURATA ELEC. NORTH AMERICA | GRM155R71H682K | 1 | G | C195 |  |  |  |  |  |  |
|  |  |  |  |  | 7 | 62011AM00-012-G |  | CAP,6.8nF,+/-10%,X7R,50V,G,SMD0402 | WALSIN TECHNOLOGY CORPORATION | 0402B682K500CT |  | G |  |  |  |  |  |  |  |
|  |  |  |  |  | 7 | 62011AM00-026-G |  | CAP,6.8nF,+/-10%,X7R,50V,G,SMD0402 | SAMSUNG SEMICONDUCTOR | CL05B682KB5NNNC |  | G |  |  |  |  |  |  |  |
|  |  |  |  | 8 | 8 | 620105E00-015-G |  | CAP,1uF,+/-10%,X7R,10V,G,SMD0603 | MURATA ELEC. NORTH AMERICA | GRM188R71A105K | 2 | G | C197,C215 |  |  |  |  |  |  |
|  |  |  |  |  | 8 | 620105E00-012-G |  | CAP,1uF,+/-10%,X7R,10V,G,SMD0603 | WALSIN TECHNOLOGY CORPORATION | 0603B105K100CT |  | G |  |  |  |  |  |  |  |
|  |  |  |  |  | 8 | 620105E00-011-G |  | CAP,1uF,+/-10%,X7R,10V,G,SMD0603 | YAGEO CORPORATION COMPONENT | CC0603KRX7R6BB105 |  | G |  |  |  |  |  |  |  |
|  |  |  |  |  | 8 | 620105E00-026-G |  | CAP,1uF,+/-10%,X7R,10V,G,SMD0603 | SAMSUNG SEMICONDUCTOR | CL10B105KP8NNNC |  | G |  |  |  |  |  |  |  |
|  |  |  |  |  | 8 | 620105E01-023-G |  | CAP,1uF,+/-10%,X7R,10V,G,SMD0603 | TAIYO ELECTRIC IND.CO.LTD | LMK107B7105KA-T |  | G |  |  |  |  |  |  |  |
|  |  |  |  | 9 | 9 | 620103600-015-G | - | CAP,10nF,+/-10%,X7R,25V,G,SMD0402 | MURATA ELEC. NORTH AMERICA | GRM155R71E103K | 14 | G | C199,C202,C203,C204,C205,C218,C219,C220,C221,C222,C2243,C2244,C2251,C2252 |  |  |  |  |  |  |
|  |  |  |  |  | 9 | 620103600-012-G |  | CAP,10nF,+/-10%,X7R,25V,G,SMD0402 | WALSIN TECHNOLOGY CORPORATION | 0402B103K250CT |  | G |  |  |  |  |  |  |  |
|  |  |  |  |  | 9 | 620103600-011-G |  | CAP,10nF,+/-10%,X7R,25V,G,SMD0402 | YAGEO CORPORATION COMPONENT | CC0402KRX7R8BB103 |  | G |  |  |  |  |  |  |  |
|  |  |  |  |  | 9 | 620103600-026-G |  | CAP,10nF,+/-10%,X7R,25V,G,SMD0402 | SAMSUNG SEMICONDUCTOR | CL05B103KA5NNNC |  | G |  |  |  |  |  |  |  |
|  |  |  |  |  | 9 | 620103601-023-G |  | CAP,10nF,+/-10%,X7R,25V,G,SMD0402 | TAIYO ELECTRIC IND.CO.LTD | TMK105B7103KV-F |  | G |  |  |  |  |  |  |  |
|  |  |  |  | 10 | 10 | 62010L000-015-G | - | CAP,10uF,+/-20%,X5R,6.3V,G,SMD0603 | MURATA ELEC. NORTH AMERICA | GRM188R60J106M | 2 | G | C200,C214 |  |  |  |  |  |  |
|  |  |  |  |  | 10 | 62010L000-023-G |  | CAP,10uF,+/-20%,X5R,6.3V,G,SMD0603 | TAIYO ELECTRIC IND.CO.LTD | JMK107BJ106MA-T |  | G |  |  |  |  |  |  |  |
|  |  |  |  |  | 10 | 62010L000-012-G |  | CAP,10uF,+/-20%,X5R,6.3V,G,SMD0603 | WALSIN TECHNOLOGY CORPORATION | 0603X106M6R3CT |  | G |  |  |  |  |  |  |  |
|  |  |  |  |  | 10 | 62010L000-026-G |  | CAP,10uF,+/-20%,X5R,6.3V,G,SMD0603 | SAMSUNG SEMICONDUCTOR | CL10A106MQ8NNNC |  | G |  |  |  |  |  |  |  |
|  |  |  |  |  | 10 | 62010L000-011-G |  | CAP,10uF,+/-20%,X5R,6.3V,G,SMD0603 | YAGEO CORPORATION COMPONENT | CC0603MRX5R5BB106 |  | G |  |  |  |  |  |  |  |
|  |  |  |  | 11 | 11 | 62011NF01-015-G |  | CAP,2.2uF,+/-10%,X7R,25V,G,SMD0805 | MURATA ELEC. NORTH AMERICA | GRM21BR71E225K | 2 | G | C206,C223 |  |  |  |  |  |  |
|  |  |  |  |  | 11 | 62011NF00-026-G |  | CAP,2.2uF,+/-10%,X7R,25V,G,SMD0805 | SAMSUNG SEMICONDUCTOR | CL21B225KAFNNNE |  | G |  |  |  |  |  |  |  |
|  |  |  |  |  | 11 | 62011NF00-023-G |  | CAP,2.2uF,+/-10%,X7R,25V,G,SMD0805 | TAIYO ELECTRIC IND.CO.LTD | TMK212B7225KG-TR |  | G |  |  |  |  |  |  |  |
|  |  |  |  | 12 | 12 | 620114000-015-G |  | CAP,10uF,+/-10%,X5R,16V,G,SMD0805 | MURATA ELEC. NORTH AMERICA | GRM21BR61C106K | 3 | G | C1946,C2081,C2253 |  |  |  |  |  |  |
|  |  |  |  |  | 12 | 620114005-023-G |  | CAP,10uF,+/-10%,X5R,16V,G,SMD0805 | TAIYO ELECTRIC IND.CO.LTD | EMK212ABJ106KG-T |  | G |  |  |  |  |  |  |  |
|  |  |  |  |  | 12 | 620114000-026-G |  | CAP,10uF,+/-10%,X5R,16V,G,SMD0805 | SAMSUNG SEMICONDUCTOR | CL21A106KOQNNNE |  | G |  |  |  |  |  |  |  |
|  |  |  |  |  | 12 | 620114000-012-G |  | CAP,10uF,+/-10%,X5R,16V,G,SMD0805 | WALSIN TECHNOLOGY CORPORATION | 0805X106K160CT |  | G |  |  |  |  |  |  |  |
|  |  |  |  | 13 | 13 | 620105400-015-G |  | CAP,1uF,+/-10%,X7R,16V,G,SMD0603 | MURATA ELEC. NORTH AMERICA | GRM188R71C105K | 10 | G | C1950,C2080,C2245,C2246,C2247,C2248,C2249,C2250,C2257,C2258 |  |  |  |  |  |  |
|  |  |  |  |  | 13 | 620105400-012-G |  | CAP,1uF,+/-10%,X7R,16V,G,SMD0603 | WALSIN TECHNOLOGY CORPORATION | 0603B105K160CT |  | G |  |  |  |  |  |  |  |
|  |  |  |  |  | 13 | 620105400-011-G |  | CAP,1uF,+/-10%,X7R,16V,G,SMD0603 | YAGEO CORPORATION COMPONENT | CC0603KRX7R7BB105 |  | G |  |  |  |  |  |  |  |
|  |  |  |  |  | 13 | 620105400-026-G |  | CAP,1uF,+/-10%,X7R,16V,G,SMD0603 | SAMSUNG SEMICONDUCTOR | CL10B105KO8NNNC |  | G |  |  |  |  |  |  |  |
|  |  |  |  |  | 13 | 620105400-023-G |  | CAP,1uF,+/-10%,X7R,16V,G,SMD0603 | TAIYO ELECTRIC IND.CO.LTD | EMK107B7105KA-T |  | G |  |  |  |  |  |  |  |
|  |  |  |  | 14 | 14 | 62011LU00-015-G | - | CAP,100nF,+/-10%,X5R,16V,G,SMD0402 | MURATA ELEC. NORTH AMERICA | GRM155R61C104KA88D | 18 | G | C2198,C2208,C2209,C2210,C2211,C2212,C2213,C2214,C2215,C2216,C2217,C2218,C2219,C2220,C2221,C2222,C2223,C2224 |  |  |  |  |  |  |
|  |  |  |  |  | 14 | 620100300-023-G |  | CAP,100nF,+/-10%,X5R,16V,G,SMD0402 | TAIYO | EMK105BJ104KV-F |  | G |  |  |  |  |  |  |  |
|  |  |  |  |  | 14 | 620100300-026-G |  | CAP,100nF,+/-10%,X5R,16V,G,SMD0402 | SAMSUNG SEMICONDUCTOR | CL05A104KO5NNNC |  | G |  |  |  |  |  |  |  |
|  |  |  |  |  | 14 | 620100300-012-G |  | CAP,100nF,+/-10%,X5R,16V,G,SMD0402 | WALSIN TECHNOLOGY CORPORATION | 0402X104K160CT |  | G |  |  |  |  |  |  |  |
|  |  |  |  | 15 | 15 | 620109S00-023-G |  | CAP,4.7uF,+/-10%,X7R,10V,G,SMD0805 | TAIYO ELECTRIC IND.CO.LTD | LMK212B7475KG-T | 1 | G | C2231 |  |  |  |  |  |  |
|  |  |  |  |  | 15 | 620109S00-026-G |  | CAP,4.7uF,+/-10%,X7R,10V,G,SMD0805 | SAMSUNG SEMICONDUCTOR | CL21B475KPFNNNE |  | G |  |  |  |  |  |  |  |
|  |  |  |  |  | 15 | 620109S00-015-G |  | CAP,4.7uF,+/-10%,X7R,10V,G,SMD0805 | MURATA ELEC. NORTH AMERICA | GRM21BR71A475K |  | G |  |  |  |  |  |  |  |
|  |  |  |  | 16 | 16 | 62012UW00-015-G | - | CAP,6.8pF,+/-0.05pF,NPO(C0G),25V,G,SMD0402 | MURATA ELEC. NORTH AMERICA | GRM1555C1E6R8WA01D | 2 | G | C2268,C2269 |  |  |  |  |  |  |
|  |  |  |  |  | 16 | 62012UW00-012-G |  | CAP,6.8pF,+/-0.05pF,NPO(C0G),25V,G,SMD0402 | WALSIN TECHNOLOGY CORPORATION | 0402N6R8A250CT |  | G |  |  |  |  |  |  |  |
|  |  |  |  | 17 | 17 | 52110K100-030-G |  | LED LAMP,SML-512MWT86,Green,40mcd@If=20mA,N/A,5V,25mA,N/A,,SMD0603,2P,G | ROHM CORPORATION | SML-512MWT86 | 24 | G | LED37,LED39,LED49,LED51,LED53,LED55,LED57,LED59,LED61,LED63,LED65,LED67,LED69,LED71,LED73,LED75,LED77,LED79,LED81,LED83,LED85,LED87,LED89,LED91 |  |  |  |  |  |  |
|  |  |  |  | 18 | 18 | 52110QV00-326-G |  | LED,Yel/Yel Gre,19-223/Y2G6C-A01/2T,2.4V,25mA,G,SMD | EVERLIGHT ELECTRONICS COMPANY,LTD. | 19-223/Y2G6C-A01/2T | 24 | G | LED38,LED40,LED50,LED52,LED54,LED56,LED58,LED60,LED62,LED64,LED66,LED68,LED70,LED72,LED74,LED76,LED78,LED80,LED82,LED84,LED86,LED88,LED90,LED92 |  |  |  |  |  |  |
|  |  |  |  | 19 | 19 | 720104100-074-G |  | FB,60 Ohm@100MHz,+/-25%,3A,30mOhm,G,SMD0805 | CHILISIN ELECTRONICS CORP. | PBY201209T-600Y-N | 1 | G | L1 |  |  |  |  |  |  |
|  |  |  |  | 20 | 20 | 72010JB00-016-G |  | FB,330 Ohm@100MHz,+/-25%,1.5A,G,80mOhm,SMD0603 | TDK ELECTRONICS EUROPE GMBH | MPZ1608S331AT | 2 | G | L2,L4 |  |  |  |  |  |  |
|  |  |  |  | 21 | 21 | 72010KF01-015-G |  | FB,600 Ohm@100MHz,+/-25%,1.3A,150mOhm,G,SMD0603 | MURATA ELEC. NORTH AMERICA | BLM18KG601SN1D | 2 | G | L6,L28 |  |  |  |  |  |  |
|  |  |  |  | 22 | 22 | 720102002-129-G |  | FB,30 Ohm@100MHz,+/-25%,3A,15mOhm,G,SMD0805 | MAG.LAYERS, SCIENTIFIC-TECHNICS (KUNSHAN) CO., LTD. | GMLB-201209-0030P-N8-RM | 1 | G | L30 |  |  |  |  |  |  |
|  |  |  |  | 23 | 23 | 720105E04-016-G |  | FB,600Ohm@100MHz,+/-25%,500mA,400mOhm,SMD0603,G | TDK ELECTRONICS EUROPE GMBH | MMZ1608B601CTAH0 | 1 | G | L31 |  |  |  |  |  |  |
|  |  |  |  | 24 | 24 | 710209J00-100-G |  | OSC,25MHz,+/-25ppm,3.3V,15pF,G,SMD | TXC CORPORATION | 7X25000008 | 2 | G | OSC1,OSC2 |  |  |  |  |  |  |
|  |  |  |  | 25 | 25 | 62120HT00-024-G |  | ECAP,SPEA,100uF,+/-20%,10V,105C,G,SMD2816,ESR<=40mOhm | PANASONIC INDUSTRIAL CO.,LTD. | EEFCX1A101R | 3 | G | PSTCE3003,PFTCE3003,PETCE3003 |  |  |  |  |  |  |
|  |  |  |  | 26 | 26 | 62012PT00-015-G |  | CAP,22uF,+/-20%,X6S,16V,G,SMD0805 | MURATA ELEC. NORTH AMERICA | GRM21BC81C226M | 14 | G | PSTC2,PFTC2,PETC2,PSTC3,PFTC3,PETC3,PSRC7,PSRC8,PSRC11,PSRC12,PSRC15,PSTC3000,PFTC3000,PETC3000 |  |  |  |  |  |  |
|  |  |  |  |  | 26 | 62012PT00-023-G |  | CAP,22uF,+/-20%,X6S,16V,G,SMD0805 | TAIYO ELECTRIC IND.CO.LTD | EDK212BC6226MG-T |  | G |  |  |  |  |  |  |  |
|  |  |  |  | 27 | 27 | 620108000-015-G | - | CAP,100pF,+/-5%,NPO(C0G),50V,G,SMD0402 | MURATA ELEC. NORTH AMERICA | GRM1555C1H101J | 3 | G | PSTC4,PFTC4,PETC4 |  |  |  |  |  |  |
|  |  |  |  |  | 27 | 62010800A-012-G |  | CAP,100pF,+/-5%,NPO(C0G),50V,G,SMD0402 | WALSIN TECHNOLOGY CORPORATION | 0402N101J500CT |  | G |  |  |  |  |  |  |  |
|  |  |  |  |  | 27 | 620108000-026-G |  | CAP,100pF,+/-5%,NPO(C0G),50V,G,SMD0402 | SAMSUNG SEMICONDUCTOR | CL05C101JB5NNNC |  | G |  |  |  |  |  |  |  |
|  |  |  |  |  | 27 | 620108000-023-G |  | CAP,100pF,+/-5%,NPO(C0G),50V,G,SMD0402 | TAIYO ELECTRIC IND.CO.LTD | UMK105CG101JV-F |  | G |  |  |  |  |  |  |  |
|  |  |  |  | 28 | 28 | 62010L800-015-G | - | CAP,1nF,+/-5%,NPO(C0G),50V,G,SMD0402 | MURATA ELEC. NORTH AMERICA | GRM1555C1H102J | 3 | G | PSTC5,PFTC5,PETC5 |  |  |  |  |  |  |
|  |  |  |  |  | 28 | 62010L800-012-G |  | CAP,1nF,+/-5%,NPO(C0G),50V,G,SMD0402 | WALSIN TECHNOLOGY CORPORATION | 0402N102J500CT |  | G |  |  |  |  |  |  |  |
|  |  |  |  |  | 28 | 62010L800-026-G |  | CAP,1nF,+/-5%,NPO(C0G),50V,G,SMD0402 | SAMSUNG SEMICONDUCTOR | CL05C102JB5NNNC |  | G |  |  |  |  |  |  |  |
|  |  |  |  | 29 | 29 | 62012T500-015-G |  | CAP,22uF,+/-20%,X7S,25V,G,SMD1206 | MURATA ELEC. NORTH AMERICA | GRM31CC71E226ME11L | 41 | G | PSRC2,PSTC6,PFTC6,PETC6,PSTC7,PFTC7,PETC7,PSTC8,PFTC8,PETC8,PSTC9,PFTC9,PETC9,PSRC17,PSTC3005,PFTC3005,PETC3005,PSTC3006,PFTC3006,PETC3006,PSTC3007,PFTC3007,PETC3007,PSTC3010,PFTC3010,PETC3010,PSTC3011,PFTC3011,PETC3011,PSTC3012,PFTC3012,PETC3012,PSTC3013,PFTC3013,PETC3013,PFTC3014,PETC3014,PFTC3015,PETC3015,PFTC3016,PETC3016 |  |  |  |  |  |  |
|  |  |  |  | 30 | 30 | 620103U00-015-G | - | CAP,470pF,+/-10%,X7R,50V,G,SMD0402 | MURATA ELEC. NORTH AMERICA | GRM155R71H471K | 3 | G | PSTC10,PFTC10,PETC10 |  |  |  |  |  |  |
|  |  |  |  |  | 30 | 620103U00-012-G |  | CAP,470pF,+/-10%,X7R,50V,G,SMD0402 | WALSIN TECHNOLOGY CORPORATION | 0402B471K500CT |  | G |  |  |  |  |  |  |  |
|  |  |  |  |  | 30 | 620103U00-026-G |  | CAP,470pF,+/-10%,X7R,50V,G,SMD0402 | SAMSUNG SEMICONDUCTOR | CL05B471KB5NNNC |  | G |  |  |  |  |  |  |  |
|  |  |  |  |  | 30 | 620103U00-023-G |  | CAP,470pF,+/-10%,X7R,50V,G,SMD0402 | TAIYO ELECTRIC IND.CO.LTD | UMK105B7471KV-F |  | G |  |  |  |  |  |  |  |
|  |  |  |  | 31 | 31 | 62010FG00-015-G | - | CAP,3.3pF,+/-0.25pF,NPO(C0G),50V,G,SMD0402 | MURATA ELEC. NORTH AMERICA | GRM1555C1H3R3C | 3 | G | PSTC11,PFTC11,PETC11 |  |  |  |  |  |  |
|  |  |  |  |  | 31 | 62010FG08-012-G |  | CAP,3.3pF,+/-0.25pF,NPO(C0G),50V,G,SMD0402 | WALSIN TECHNOLOGY CORPORATION | 0402N3R3C500CT |  | G |  |  |  |  |  |  |  |
|  |  |  |  |  | 31 | 62010FG00-026-G |  | CAP,3.3pF,+/-0.25pF,NPO(C0G),50V,G,SMD0402 | SAMSUNG SEMICONDUCTOR | CL05C3R3CB5ANNC |  | G |  |  |  |  |  |  |  |
|  |  |  |  | 32 | 32 | 620107L00-015-G | - | CAP,2.2nF,+/-10%,X7R,50V,G,SMD0402 | MURATA ELEC. NORTH AMERICA | GRM155R71H222K | 3 | G | PSTC12,PFTC12,PETC12 |  |  |  |  |  |  |
|  |  |  |  |  | 32 | 620107L00-012-G |  | CAP,2.2nF,+/-10%,X7R,50V,G,SMD0402 | WALSIN TECHNOLOGY CORPORATION | 0402B222K500CT |  | G |  |  |  |  |  |  |  |
|  |  |  |  |  | 32 | 620107L00-026-G |  | CAP,2.2nF,+/-10%,X7R,50V,G,SMD0402 | SAMSUNG SEMICONDUCTOR | CL05B222KB5NNNC |  | G |  |  |  |  |  |  |  |
|  |  |  |  |  | 32 | 620107L03-023-G |  | CAP,2.2nF,+/-10%,X7R,50V,G,SMD0402 | TAIYO ELECTRIC IND.CO.LTD | UMK105B7222KV-F |  | G |  |  |  |  |  |  |  |
|  |  |  |  | 33 | 33 | 62012A400-015-G | - | CAP,100nF,+/-10%,X7R,25V,G,SMD0402 | MURATA ELEC. NORTH AMERICA | GRM155R71E104KE14D | 8 | G | PSRC1,PSRC6,PSTC3002,PFTC3002,PETC3002,PSTC3008,PFTC3008,PETC3008 |  |  |  |  |  |  |
|  |  |  |  |  | 33 | 62012A400-023-G |  | CAP,100nF,+/-10%,X7R,25V,G,SMD0402 | TAIYO ELECTRIC IND.CO.LTD | TMK105B7104KV-FR |  | G |  |  |  |  |  |  |  |
|  |  |  |  |  | 33 | 62012A400-026-G |  | CAP,100nF,+/-10%,X7R,25V,G,SMD0402 | SAMSUNG SEMICONDUCTOR | CL05B104KA5NNNC |  | G |  |  |  |  |  |  |  |
|  |  |  |  |  | 33 | 62012A400-012-G |  | CAP,100nF,+/-10%,X7R,25V,G,SMD0402 | WALSIN TECHNOLOGY CORPORATION | 0402B104K250CT |  | G |  |  |  |  |  |  |  |
|  |  |  |  | 34 | 34 | 62012T300-015-G |  | CAP,1uF,+/-10%,X7S,25V,G,SMD0402 | MURATA ELEC. NORTH AMERICA | GRM155C71E105KE11D | 4 | G | PSRC4,PSTC3003,PFTC3003,PETC3003 |  |  |  |  |  |  |
|  |  |  |  |  | 34 | 620138700-026-G |  | CAP,1uF,+/-10%,X6S,25V,G,SMD0402 | SAMSUNG SEMICONDUCTOR | CL05X105KA5NQNC |  | G |  |  |  |  |  |  |  |
|  |  |  |  |  | 34 | 620138700-015-G |  | CAP,1uF,+/-10%,X6S,25V,G,SMD0402 | MURATA | GRM155C81E105KE11D |  | G |  |  |  |  |  |  |  |
|  |  |  |  | 35 | 35 | 62012GG00-015-G |  | CAP,10uF,+/-10%,X7S,25V,G,SMD0805 | MURATA ELEC. NORTH AMERICA | GRM21BC71E106K | 7 | G | PSRC3,PSTC3004,PFTC3004,PETC3004,PSTC3009,PFTC3009,PETC3009 |  |  |  |  |  |  |
|  |  |  |  |  | 35 | 62012GG00-012-G |  | CAP,10uF,+/-10%,X7S,25V,G,SMD0805 | WALSIN TECHNOLOGY CORPORATION | 0805A106K250CT |  | G |  |  |  |  |  |  |  |
|  |  |  |  | 36 | 36 | 63035Y800-051-G |  | Coil Ind,Shielded(SHLD),820nH@100KHz,+/-20%,13A,8mOhm,SMD,7.6*6.9*3.0,,,G | PULSE ELECTRONICS (SINGAPORE) | PA4341.821NLT | 3 | G | PSTL1,PFTL1,PETL1 |  |  |  |  |  |  |
|  |  |  |  | 37 | 37 | 630362G00-065-G |  | 22nH@100KHz,+/-20%,19A,0.32mOhm,SHLD,G,SMD | Delta | HCB0430-220 | 3 | G | PSTL2,PFTL2,PETL2 |  |  |  |  |  |  |
|  |  |  |  | 38 | 38 | 61010LA00-017-G | - | RES,4.7KOhm,+/-1%,1/16W,G,SMD0402 | KOA SPEER ELECTRONICS, INC. | RK73H1ETTP4701F | 45 | G | PSTR1,PFTR1,PETR1,R336,R1605,R1700,R1701,R1702,R1703,R1704,R1705,R1706,R1707,R1708,R1709,R1710,R1711,R1712,R1713,R1714,R1715,R1716,R1717,R1718,R1719,R1720,R1721,R1722,R1723,R1724,R1725,R1726,R1727,R1728,R1729,R1730,R1731,R1732,R1733,R1734,R1735,R1736,R1737,R1738,R1739 |  |  |  |  |  |  |
|  |  |  |  |  | 38 | 61010LA00-012-G |  | RES,4.7KOhm,+/-1%,1/16W,G,SMD0402 | WALSIN TECHNOLOGY CORPORATION | WR04X4701FTL |  | G |  |  |  |  |  |  |  |
|  |  |  |  |  | 38 | 61010LA00-011-G |  | RES,4.7KOhm,+/-1%,1/16W,G,SMD0402 | YAGEO CORPORATION COMPONENT | RC0402FR-074K7L |  | G |  |  |  |  |  |  |  |
|  |  |  |  |  | 38 | 61010LA00-044-G |  | RES,4.7KOhm,+/-1%,1/16W,G,SMD0402 | TA-I TECHNOLOGY CO., LTD | RM04FTN4701 |  | G |  |  |  |  |  |  |  |
|  |  |  |  | 39 | 39 | 610107A00-017-G | - | RES,0 Ohm,+/-5%,1/16W,G,SMD0402 | KOA SPEER ELECTRONICS, INC. | RK73Z1ETTP | 146 | G | PSTR2,PFTR2,PETR2,R5,PSTR7,PFTR7,PETR7,R8,PSTR8,PSRR8,PFTR8,PETR8,PSRR9,R10,PSTR14,PFTR14,PETR14,PSRR15,PSRR18,PSTR22,PSRR22,PFTR22,PETR22,R60,R65,R511,R568,R569,R570,R571,R1888,R1889,R1890,R1891,R1892,R1893,R1894,R1895,R1896,R1897,R1898,R1899,R1900,R1901,R1902,R1903,R1988,R1989,R1990,R1991,R1992,R1993,R1994,R1995,R1996,R1997,R1998,R1999,R2000,R2001,R2002,R2003,R2004,R2005,R2006,R2007,R2008,R2009,R2010,R2011,R2012,R2013,R2014,R2015,R2016,R2017,R2018,R2019,R2020,R2021,R2022,R2023,R2024,R2025,R2026,R2027,R2028,R2029,R2030,R2031,R2032,R2033,R2034,R2035,R2036,R2037,R2038,R2039,R2040,R2041,R2042,R2043,R2044,R2045,R2046,R2047,R2061,R2066,R2067,R2070,R2085,R2086,R2152,R2153,R2154,R2155,R2158,R2180,R2181,R2182,R2183,R2184,R2185,R2186,R2187,R2188,R2189,R2190,R2191,R2192,R2193,R2194,R2195,R2196,R2197,R2198,R2199,PSTR3001,PFTR3001,PETR3001,PSTR3002,PFTR3002,PETR3002,PSTR3003,PFTR3003,PETR3003 |  |  |  |  |  |  |
|  |  |  |  |  | 39 | 610107A00-012-G |  | RES,0 Ohm,+/-5%,1/16W,G,SMD0402 | WALSIN TECHNOLOGY CORPORATION | WR04X000PTL |  | G |  |  |  |  |  |  |  |
|  |  |  |  |  | 39 | 610107A00-011-G |  | RES,0 Ohm,+/-5%,1/16W,G,SMD0402 | YAGEO CORPORATION COMPONENT | RC0402JR-070RL |  | G |  |  |  |  |  |  |  |
|  |  |  |  |  | 39 | 610107A00-044-G |  | RES,0 Ohm,+/-5%,1/16W,G,SMD0402 | TA-I TECHNOLOGY CO., LTD | RM04JTN0 |  | G |  |  |  |  |  |  |  |
|  |  |  |  |  | 39 | 610107A00-024-G |  | RES,0 Ohm,+/-5%,1/16W,G,SMD0402 | PANASONIC INDUSTRIAL CO.,LTD. | ERJ2GE0R00X |  | G |  |  |  |  |  |  |  |
|  |  |  |  |  | 39 | 610107A00-029-G |  | RES,0 Ohm,+/-5%,1/16W,G,SMD0402 | VISHAY ENTER TECHNO LOGY.INC | CRCW04020000Z0ED |  | G |  |  |  |  |  |  |  |
|  |  |  |  | 40 | 40 | 61011HA00-017-G |  | RES,1 Ohm,+/-1%,1/16W,G,SMD0402 | KOA SPEER ELECTRONICS, INC. | RK73H1ETTP1R00F | 4 | G | PSTR4,PFTR4,PETR4,PSRR5 |  |  |  |  |  |  |
|  |  |  |  |  | 40 | 61011HA00-012-G |  | RES,1 Ohm,+/-1%,1/16W,G,SMD0402 | WALSIN TECHNOLOGY CORPORATION | WR04W1R00FTL |  | G |  |  |  |  |  |  |  |
|  |  |  |  |  | 40 | 61011HA00-011-G |  | RES,1 Ohm,+/-1%,1/16W,G,SMD0402 | YAGEO CORPORATION COMPONENT | RC0402FR-071RL |  | G |  |  |  |  |  |  |  |
|  |  |  |  |  | 40 | 61011HA00-044-G |  | RES,1 Ohm,+/-1%,1/16W,G,SMD0402 | TA-I TECHNOLOGY CO., LTD | RM04FTN1R00 |  | G |  |  |  |  |  |  |  |
|  |  |  |  |  | 40 | 61011HA00-029-G |  | RES,1 Ohm,+/-1%,1/16W,G,SMD0402 | VISHAY ENTER TECHNO LOGY.INC | CRCW04021R00FNED |  | G |  |  |  |  |  |  |  |
|  |  |  |  | 41 | 41 | 61100QD00-011-G |  | RES,787 Ohm,+/-0.1%,1/16W,G,SMD0402 | YAGEO CORPORATION COMPONENT | RT0402BRD07787RL | 3 | G | PSTR5,PFTR5,PETR5 |  |  |  |  |  |  |
|  |  |  |  | 42 | 42 | 61100SU00-011-G |  | RES,105 Ohm,+/-0.1%,1/16W,G,SMD0402 | YAGEO CORPORATION COMPONENT | RT0402BRD07105RL | 3 | G | PSTR6,PFTR6,PETR6 |  |  |  |  |  |  |
|  |  |  |  | 43 | 43 | 61011BD00-017-G |  | RES,46.4KOhm,+/-1%,1/16W,G,SMD0402 | KOA SPEER ELECTRONICS, INC. | RK73H1ETTP4642F | 3 | G | PSTR9,PFTR9,PETR9 |  |  |  |  |  |  |
|  |  |  |  |  | 43 | 61011BD00-011-G |  | RES,46.4KOhm,+/-1%,1/16W,G,SMD0402 | YAGEO CORPORATION COMPONENT | RC0402FR-0746K4L |  | G |  |  |  |  |  |  |  |
|  |  |  |  |  | 43 | 61011BD00-012-G |  | RES,46.4KOhm,+/-1%,1/16W,G,SMD0402 | WALSIN TECHNOLOGY CORPORATION | WR04X4642FTL |  | G |  |  |  |  |  |  |  |
|  |  |  |  |  | 43 | 61011BD00-044-G |  | RES,46.4KOhm,+/-1%,1/16W,G,SMD0402 | TA-I TECHNOLOGY CO., LTD | RM04FTN4642 |  | G |  |  |  |  |  |  |  |
|  |  |  |  | 44 | 44 | 610124U00-017-G | - | RES,7.87KOhm,+/-1%,1/16W,G,SMD0402 | KOA SPEER ELECTRONICS, INC. | RK73H1ETTP7871F | 3 | G | PSTR10,PFTR10,PETR10 |  |  |  |  |  |  |
|  |  |  |  |  | 44 | 610124U00-012-G |  | RES,7.87KOhm,+/-1%,1/16W,G,SMD0402 | WALSIN TECHNOLOGY CORPORATION | WR04X7871FTL |  | G |  |  |  |  |  |  |  |
|  |  |  |  |  | 44 | 610124U00-011-G |  | RES,7.87KOhm,+/-1%,1/16W,G,SMD0402 | YAGEO CORPORATION COMPONENT | RC0402FR-077K87L |  | G |  |  |  |  |  |  |  |
|  |  |  |  |  | 44 | 610124U00-044-G |  | RES,7.87KOhm,+/-1%,1/16W,G,SMD0402 | TA-I TECHNOLOGY CO., LTD | RM04FTN7871 |  | G |  |  |  |  |  |  |  |
|  |  |  |  | 45 | 45 | 610112J00-017-G | - | RES,200 Ohm,+/-1%,1/16W,G,SMD0402 | KOA SPEER ELECTRONICS, INC. | RK73H1ETTP2000F | 3 | G | PSTR11,PFTR11,PETR11 |  |  |  |  |  |  |
|  |  |  |  |  | 45 | 610112J00-012-G |  | RES,200 Ohm,+/-1%,1/16W,G,SMD0402 | WALSIN TECHNOLOGY CORPORATION | WR04X2000FTL |  | G |  |  |  |  |  |  |  |
|  |  |  |  |  | 45 | 610112J00-011-G |  | RES,200 Ohm,+/-1%,1/16W,G,SMD0402 | YAGEO CORPORATION COMPONENT | RC0402FR-07200RL |  | G |  |  |  |  |  |  |  |
|  |  |  |  |  | 45 | 610112J00-044-G |  | RES,200 Ohm,+/-1%,1/16W,G,SMD0402 | TA-I TECHNOLOGY CO., LTD | RM04FTN2000 |  | G |  |  |  |  |  |  |  |
|  |  |  |  |  | 45 | 610112J00-029-G |  | RES,200 Ohm,+/-1%,1/16W,G,SMD0402 | VISHAY ENTER TECHNO LOGY.INC | CRCW0402200RFKED |  | G |  |  |  |  |  |  |  |
|  |  |  |  |  | 45 | 610112J00-024-G |  | RES,200 Ohm,+/-1%,1/16W,G,SMD0402 | PANASONIC INDUSTRIAL CO.,LTD. | ERJ2RKF2000X |  | G |  |  |  |  |  |  |  |
|  |  |  |  | 46 | 46 | 61011JY00-017-G | - | RES,39.2KOhm,+/-1%,1/16W,G,SMD0402 | KOA SPEER ELECTRONICS, INC. | RK73H1ETTP3922F | 3 | G | PSTR15,PFTR15,PETR15 |  |  |  |  |  |  |
|  |  |  |  |  | 46 | 61011JY00-012-G |  | RES,39.2KOhm,+/-1%,1/16W,G,SMD0402 | WALSIN TECHNOLOGY CORPORATION | WR04X3922FTL |  | G |  |  |  |  |  |  |  |
|  |  |  |  |  | 46 | 61011JY00-011-G |  | RES,39.2KOhm,+/-1%,1/16W,G,SMD0402 | YAGEO CORPORATION COMPONENT | RC0402FR-0739K2L |  | G |  |  |  |  |  |  |  |
|  |  |  |  |  | 46 | 61011JY00-044-G |  | RES,39.2KOhm,+/-1%,1/16W,G,SMD0402 | TA-I TECHNOLOGY CO., LTD | RM04FTN3922 |  | G |  |  |  |  |  |  |  |
|  |  |  |  |  | 46 | 61011JY00-029-G |  | RES,39.2KOhm,+/-1%,1/16W,G,SMD0402 | VISHAY ENTER TECHNO LOGY.INC | CRCW040239K2FKED |  | G |  |  |  |  |  |  |  |
|  |  |  |  | 47 | 47 | 32013P700-238-G |  | IC,Regulator,IR3448MTRPBF,ADJ,16A,G,PQFN-33,SMD | INTERNATIONAL RECTIFIER | IR3448MTRPBF | 3 | G | PSTU1,PFTU1,PETU1 |  |  |  |  |  |  |
|  |  |  |  | 48 | 48 | 62012P100-015-G |  | CAP,2.2uF,+/-20%,X7S,10V,G,SMD0402 | MURATA ELEC. NORTH AMERICA | GRM155C71A225M | 1 | G | PSRC5 |  |  |  |  |  |  |
|  |  |  |  |  | 48 | 62012P100-012-G |  | CAP,2.2uF,+/-20%,X7S,10V,G,SMD0402 | WALSIN TECHNOLOGY CORPORATION | 0402A225M100CT |  | G |  |  |  |  |  |  |  |
|  |  |  |  | 49 | 49 | 620105U00-015-G | - | CAP,220pF,+/-10%,X7R,50V,G,SMD0402 | MURATA ELEC. NORTH AMERICA | GRM155R71H221K | 1 | G | PSRC14 |  |  |  |  |  |  |
|  |  |  |  |  | 49 | 620105U00-012-G |  | CAP,220pF,+/-10%,X7R,50V,G,SMD0402 | WALSIN TECHNOLOGY CORPORATION | 0402B221K500CT |  | G |  |  |  |  |  |  |  |
|  |  |  |  |  | 49 | 620105U00-026-G |  | CAP,220pF,+/-10%,X7R,50V,G,SMD0402 | SAMSUNG SEMICONDUCTOR | CL05B221KB5NNNC |  | G |  |  |  |  |  |  |  |
|  |  |  |  | 50 | 50 | 62012H100-015-G |  | CAP,10uF,+/-20%,X6S,10V,G,SMD0603 | MURATA ELEC. NORTH AMERICA | GRM188C81A106M | 1 | G | PSRC16 |  |  |  |  |  |  |
|  |  |  |  |  | 50 | 62012H100-023-G |  | CAP,10uF,+/-20%,X6S,10V,G,SMD0603 | TAIYO ELECTRIC IND.CO.LTD | LMK107BC6106MA-T |  | G |  |  |  |  |  |  |  |
|  |  |  |  |  | 50 | 62012H100-026-G |  | CAP,10uF,+/-20%,X6S,10V,G,SMD0603 | SAMSUNG SEMICONDUCTOR | CL10X106MP8NRNC |  | G |  |  |  |  |  |  |  |
|  |  |  |  | 51 | 51 | 72010SJ00-059-G |  | FB,Multilayer,10mOhm,26Ohm@100MHz,+/-25%,6A,,SMD0603,G | TAI-TECH ADVANCED ELECTRONICS CO., LTD. | HCB1608KF-260T60 | 1 | G | PSRL1 |  |  |  |  |  |  |
|  |  |  |  | 52 | 52 | 63030PW00-034-G |  | Coil Ind,Shielded(SHLD),4.7uH@100KHz,+/-20%,5.5A,40mOhm,SMD,7.3*6.6*3.0,G | CYNTEC CO. LTD | PCMC063T-4R7MN | 1 | G | PSRL2 |  |  |  |  |  |  |
|  |  |  |  | 53 | 53 | 610117D00-017-G | - | RES,13.3KOhm,+/-1%,1/16W,G,SMD0402 | KOA SPEER ELECTRONICS, INC. | RK73H1ETTP1332F | 1 | G | PSRR1 |  |  |  |  |  |  |
|  |  |  |  |  | 53 | 610117D00-012-G |  | RES,13.3KOhm,+/-1%,1/16W,G,SMD0402 | WALSIN TECHNOLOGY CORPORATION | WR04X1332FTL |  | G |  |  |  |  |  |  |  |
|  |  |  |  |  | 53 | 610117D00-011-G |  | RES,13.3KOhm,+/-1%,1/16W,G,SMD0402 | YAGEO CORPORATION COMPONENT | RC0402FR-0713K3L |  | G |  |  |  |  |  |  |  |
|  |  |  |  |  | 53 | 610117D00-044-G |  | RES,13.3KOhm,+/-1%,1/16W,G,SMD0402 | TA-I TECHNOLOGY CO., LTD | RM04FTN1332 |  | G |  |  |  |  |  |  |  |
|  |  |  |  | 54 | 54 | 610114S00-017-G | - | RES,4.99KOhm,+/-1%,1/16W,G,SMD0402 | KOA SPEER ELECTRONICS, INC. | RK73H1ETTP4991F | 1 | G | PSRR3 |  |  |  |  |  |  |
|  |  |  |  |  | 54 | 610114S00-012-G |  | RES,4.99KOhm,+/-1%,1/16W,G,SMD0402 | WALSIN TECHNOLOGY CORPORATION | WR04X4991FTL |  | G |  |  |  |  |  |  |  |
|  |  |  |  |  | 54 | 610114S00-011-G |  | RES,4.99KOhm,+/-1%,1/16W,G,SMD0402 | YAGEO CORPORATION COMPONENT | RC0402FR-074K99L |  | G |  |  |  |  |  |  |  |
|  |  |  |  |  | 54 | 610114S00-044-G |  | RES,4.99KOhm,+/-1%,1/16W,G,SMD0402 | TA-I TECHNOLOGY CO., LTD | RM04FTN4991 |  | G |  |  |  |  |  |  |  |
|  |  |  |  |  | 54 | 610114S00-024-G |  | RES,4.99KOhm,+/-1%,1/16W,G,SMD0402 | PANASONIC INDUSTRIAL CO.,LTD. | ERJ2RKF4991X |  | G |  |  |  |  |  |  |  |
|  |  |  |  | 55 | 55 | 61010G500-017-G | - | RES,10KOhm,+/-1%,1/16W,G,SMD0402 | KOA SPEER ELECTRONICS, INC. | RK73H1ETTP1002F | 1 | G | PSRR6 |  |  |  |  |  |  |
|  |  |  |  |  | 55 | 61010G500-012-G |  | RES,10KOhm,+/-1%,1/16W,G,SMD0402 | WALSIN TECHNOLOGY CORPORATION | WR04X1002FTL |  | G |  |  |  |  |  |  |  |
|  |  |  |  |  | 55 | 61010G500-011-G |  | RES,10KOhm,+/-1%,1/16W,G,SMD0402 | YAGEO CORPORATION COMPONENT | RC0402FR-0710KL |  | G |  |  |  |  |  |  |  |
|  |  |  |  |  | 55 | 61010G500-044-G |  | RES,10KOhm,+/-1%,1/16W,G,SMD0402 | TA-I TECHNOLOGY CO., LTD | RM04FTN1002 |  | G |  |  |  |  |  |  |  |
|  |  |  |  |  | 55 | 61010G500-029-G |  | RES,10KOhm,+/-1%,1/16W,G,SMD0402 | VISHAY ENTER TECHNO LOGY.INC | CRCW040210K0FKED |  | G |  |  |  |  |  |  |  |
|  |  |  |  |  | 55 | 61010G500-024-G |  | RES,10KOhm,+/-1%,1/16W,G,SMD0402 | PANASONIC INDUSTRIAL CO.,LTD. | ERJ2RKF1002X |  | G |  |  |  |  |  |  |  |
|  |  |  |  | 56 | 56 | 611004M00-024-G |  | RES,16.5KOhm,+/-0.1%,1/16W,G,SMD0402 | PANASONIC INDUSTRIAL CO.,LTD. | ERA2AEB1652X | 1 | G | PSRR17 |  |  |  |  |  |  |
|  |  |  |  | 57 | 57 | 61100YB00-011-G |  | RES,2.94KOhm,+/-0.1%,1/16W,G,SMD0402 | YAGEO CORPORATION COMPONENT | RT0402BRD072K94L | 1 | G | PSRR19 |  |  |  |  |  |  |
|  |  |  |  | 58 | 58 | 32013PD00-238-G |  | IC,Regulator,IR3883MTRPbF,ADJ,3A,G,QFN-16,SMD | INTERNATIONAL RECTIFIER | IR3883MTRPBF | 1 | G | PSRU1 |  |  |  |  |  |  |
|  |  |  |  | 59 | 59 | 510507900-223-G |  | MOS N/N,NTJD4001NT1G,30V,0.25A,1.5ohm@4V,G,SOT363-6,SMD | ON SEMICONDUCTOR CORP | NTJD4001NT1G | 25 | G | QN19,QN20,QN25,QN26,QN27,QN28,QN29,QN30,QN31,QN33,QN34,QN35,QN36,QN37,QN38,QN39,QN40,QN41,QN42,QN43,QN44,QN45,QN46,QN47,QN48 |  |  |  |  |  |  |
|  |  |  |  | 60 | 60 | 61011H500-017-G | - | RES,22 Ohm,+/-1%,1/16W,G,SMD0402 | KOA SPEER ELECTRONICS, INC. | RK73H1ETTP22R0F | 12 | G | R1,R14,R338,R504,R509,R531,R550,R552,R572,R868,R869,R2148 |  |  |  |  |  |  |
|  |  |  |  |  | 60 | 61011H500-012-G |  | RES,22 Ohm,+/-1%,1/16W,G,SMD0402 | WALSIN TECHNOLOGY CORPORATION | WR04X22R0FTL |  | G |  |  |  |  |  |  |  |
|  |  |  |  |  | 60 | 61011H500-011-G |  | RES,22 Ohm,+/-1%,1/16W,G,SMD0402 | YAGEO CORPORATION COMPONENT | RC0402FR-0722RL |  | G |  |  |  |  |  |  |  |
|  |  |  |  |  | 60 | 61011H500-044-G |  | RES,22 Ohm,+/-1%,1/16W,G,SMD0402 | TA-I TECHNOLOGY CO., LTD | RM04FTN22R0 |  | G |  |  |  |  |  |  |  |
|  |  |  |  |  | 60 | 61011H500-024-G |  | RES,22 Ohm,+/-1%,1/16W,G,SMD0402 | PANASONIC INDUSTRIAL CO.,LTD. | ERJ2RKF22R0X |  | G |  |  |  |  |  |  |  |
|  |  |  |  | 61 | 61 | 61011MQ00-017-G | - | RES,4.75KOhm,+/-1%,1/16W,G,SMD0402 | KOA SPEER ELECTRONICS, INC. | RK73H1ETTP4751F | 2 | G | R2,R4 |  |  |  |  |  |  |
|  |  |  |  |  | 61 | 61011MQ00-011-G |  | RES,4.75KOhm,+/-1%,1/16W,G,SMD0402 | YAGEO CORPORATION COMPONENT | RC0402FR-074K75L |  | G |  |  |  |  |  |  |  |
|  |  |  |  |  | 61 | 61011MQ00-012-G |  | RES,4.75KOhm,+/-1%,1/16W,G,SMD0402 | WALSIN TECHNOLOGY CORPORATION | WR04X4751FTL |  | G |  |  |  |  |  |  |  |
|  |  |  |  |  | 61 | 61011MQ00-044-G |  | RES,4.75KOhm,+/-1%,1/16W,G,SMD0402 | TA-I TECHNOLOGY CO., LTD | RM04FTN4751 |  | G |  |  |  |  |  |  |  |
|  |  |  |  | 62 | 62 | 610107B00-017-G | K9576 | RES,4.7KOhm,+/-5%,1/16W,G,SMD0402 | KOA SPEER ELECTRONICS, INC. | RK73B1ETTP472J | 134 | G | R6,R7,R9,R16,R17,R18,R62,R228,R312,R323,R324,R331,R333,R337,R411,R413,R417,R427,R429,R433,R443,R445,R448,R460,R461,R465,R475,R477,R480,R492,R493,R497,R503,R505,R506,R507,R510,R512,R513,R514,R516,R527,R528,R541,R546,R547,R548,R549,R553,R555,R556,R557,R559,R560,R617,R619,R622,R634,R635,R639,R649,R651,R654,R666,R667,R671,R681,R683,R686,R698,R699,R703,R713,R715,R718,R730,R731,R735,R745,R747,R750,R762,R763,R767,R777,R779,R782,R794,R795,R799,R809,R811,R814,R826,R827,R831,R841,R843,R846,R858,R859,R863,R866,R1078,R1079,R1603,R1668,R1681,R1684,R1688,R1694,R1697,R1783,R2128,R2129,R2130,R2131,R2132,R2133,R2134,R2135,R2136,R2137,R2138,R2139,R2140,R2141,R2142,R2143,R2144,R2145,R2146,R2147,R2149 |  |  |  |  |  |  |
|  |  |  |  |  | 62 | 610107B00-012-G |  | RES,4.7KOhm,+/-5%,1/16W,G,SMD0402 | WALSIN TECHNOLOGY CORPORATION | WR04X472JTL |  | G |  |  |  |  |  |  |  |
|  |  |  |  |  | 62 | 610107B00-011-G |  | RES,4.7KOhm,+/-5%,1/16W,G,SMD0402 | YAGEO CORPORATION COMPONENT | RC0402JR-074K7L |  | G |  |  |  |  |  |  |  |
|  |  |  |  |  | 62 | 610107B00-044-G |  | RES,4.7KOhm,+/-5%,1/16W,G,SMD0402 | TA-I TECHNOLOGY CO., LTD | RM04JTN472 |  | G |  |  |  |  |  |  |  |
|  |  |  |  |  | 62 | 610107B00-024-G |  | RES,4.7KOhm,+/-5%,1/16W,G,SMD0402 | PANASONIC INDUSTRIAL CO.,LTD. | ERJ2GEJ472X |  | G |  |  |  |  |  |  |  |
|  |  |  |  |  | 62 | 610107B00-029-G |  | RES,4.7KOhm,+/-5%,1/16W,G,SMD0402 | VISHAY ENTER TECHNO LOGY.INC | CRCW04024K70JNED |  | G |  |  |  |  |  |  |  |
|  |  |  |  | 63 | 63 | 61010JY00-017-G | - | RES,220 Ohm,+/-5%,1/16W,G,SMD0402 | KOA SPEER ELECTRONICS, INC. | RK73B1ETTP221J | 10 | G | R12,R15,R1672,R1673,R1679,R1683,R1687,R1698,R1780,R1782 |  |  |  |  |  |  |
|  |  |  |  |  | 63 | 61010JY00-012-G |  | RES,220 Ohm,+/-5%,1/16W,G,SMD0402 | WALSIN TECHNOLOGY CORPORATION | WR04X221JTL |  | G |  |  |  |  |  |  |  |
|  |  |  |  |  | 63 | 61010JY00-011-G |  | RES,220 Ohm,+/-5%,1/16W,G,SMD0402 | YAGEO CORPORATION COMPONENT | RC0402JR-07220RL |  | G |  |  |  |  |  |  |  |
|  |  |  |  |  | 63 | 61010JY00-044-G |  | RES,220 Ohm,+/-5%,1/16W,G,SMD0402 | TA-I TECHNOLOGY CO., LTD | RM04JTN221 |  | G |  |  |  |  |  |  |  |
|  |  |  |  | 64 | 64 | 610101V00-017-G | K9572 | RES,22 Ohm,+/-5%,1/16W,G,SMD0402 | KOA SPEER ELECTRONICS, INC. | RK73B1ETTP220J | 40 | G | R106,R1740,R1741,R1742,R1743,R1744,R1745,R1746,R1747,R1748,R1749,R1750,R1751,R1752,R1753,R1754,R1755,R1756,R1757,R1758,R1759,R1760,R1761,R1762,R1763,R1764,R1765,R1766,R1767,R1768,R1769,R1770,R1771,R1772,R1773,R1774,R1775,R1776,R1777,R1778 |  |  |  |  |  |  |
|  |  |  |  |  | 64 | 610101V00-012-G |  | RES,22 Ohm,+/-5%,1/16W,G,SMD0402 | WALSIN TECHNOLOGY CORPORATION | WR04X220JTL |  | G |  |  |  |  |  |  |  |
|  |  |  |  |  | 64 | 610101V00-011-G |  | RES,22 Ohm,+/-5%,1/16W,G,SMD0402 | YAGEO CORPORATION COMPONENT | RC0402JR-0722RL |  | G |  |  |  |  |  |  |  |
|  |  |  |  |  | 64 | 610101V00-044-G |  | RES,22 Ohm,+/-5%,1/16W,G,SMD0402 | TA-I TECHNOLOGY CO., LTD | RM04JTN220 |  | G |  |  |  |  |  |  |  |
|  |  |  |  |  | 64 | 610101V00-024-G |  | RES,22 Ohm,+/-5%,1/16W,G,SMD0402 | PANASONIC INDUSTRIAL CO.,LTD. | ERJ2GEJ220X |  | G |  |  |  |  |  |  |  |
|  |  |  |  | 65 | 65 | 610118100-017-G | - | RES,1.4KOhm,+/-1%,1/16W,G,SMD0402 | KOA SPEER ELECTRONICS, INC. | RK73H1ETTP1401F | 2 | G | R251,R252 |  |  |  |  |  |  |
|  |  |  |  |  | 65 | 610118100-012-G |  | RES,1.4KOhm,+/-1%,1/16W,G,SMD0402 | WALSIN TECHNOLOGY CORPORATION | WR04X1401FTL |  | G |  |  |  |  |  |  |  |
|  |  |  |  |  | 65 | 610118100-011-G |  | RES,1.4KOhm,+/-1%,1/16W,G,SMD0402 | YAGEO CORPORATION COMPONENT | RC0402FR-071K4L |  | G |  |  |  |  |  |  |  |
|  |  |  |  |  | 65 | 610118100-044-G |  | RES,1.4KOhm,+/-1%,1/16W,G,SMD0402 | TA-I TECHNOLOGY CO., LTD | RM04FTN1401 |  | G |  |  |  |  |  |  |  |
|  |  |  |  |  | 65 | 610118100-024-G |  | RES,1.4KOhm,+/-1%,1/16W,G,SMD0402 | PANASONIC INDUSTRIAL CO.,LTD. | ERJ2RKF1401X |  | G |  |  |  |  |  |  |  |
|  |  |  |  | 66 | 66 | 61010BG00-017-G | RJ328 | RES,100 Ohm,+/-1%,1/10W,G,SMD0603 | KOA SPEER ELECTRONICS, INC. | RK73H1JTTD1000F | 72 | G | R313,R317,R319,R330,R332,R335,R410,R412,R415,R426,R428,R431,R442,R444,R447,R458,R459,R463,R474,R476,R479,R490,R491,R495,R616,R618,R621,R632,R633,R637,R648,R650,R653,R664,R665,R669,R680,R682,R685,R696,R697,R701,R712,R714,R717,R728,R729,R733,R744,R746,R749,R760,R761,R765,R776,R778,R781,R792,R793,R797,R808,R810,R813,R824,R825,R829,R840,R842,R845,R856,R857,R861 |  |  |  |  |  |  |
|  |  |  |  |  | 66 | 61010BG00-012-G |  | RES,100 Ohm,+/-1%,1/10W,G,SMD0603 | WALSIN TECHNOLOGY CORPORATION | WR06X1000FTL |  | G |  |  |  |  |  |  |  |
|  |  |  |  |  | 66 | 61010BG00-011-G |  | RES,100 Ohm,+/-1%,1/10W,G,SMD0603 | YAGEO CORPORATION COMPONENT | RC0603FR-07100RL |  | G |  |  |  |  |  |  |  |
|  |  |  |  | 67 | 67 | 61011QA00-017-G | - | RES,24KOhm,+/-5%,1/16W,G,SMD0402 | KOA SPEER ELECTRONICS, INC. | RK73B1ETTP243J | 24 | G | R314,R327,R407,R423,R439,R454,R471,R486,R613,R628,R645,R660,R677,R692,R709,R724,R741,R756,R773,R788,R805,R820,R837,R852 |  |  |  |  |  |  |
|  |  |  |  |  | 67 | 61011QA00-011-G |  | RES,24KOhm,+/-5%,1/16W,G,SMD0402 | YAGEO CORPORATION COMPONENT | RC0402JR-0724KL |  | G |  |  |  |  |  |  |  |
|  |  |  |  |  | 67 | 61011QA00-012-G |  | RES,24KOhm,+/-5%,1/16W,G,SMD0402 | WALSIN TECHNOLOGY CORPORATION | WR04X243JTL |  | G |  |  |  |  |  |  |  |
|  |  |  |  |  | 67 | 61011QA00-044-G |  | RES,24KOhm,+/-5%,1/16W,G,SMD0402 | TA-I TECHNOLOGY CO., LTD | RM04JTN243 |  | G |  |  |  |  |  |  |  |
|  |  |  |  | 68 | 68 | 610115Y00-017-G | - | RES,16.2KOhm,+/-1%,1/16W,G,SMD0402 | KOA SPEER ELECTRONICS, INC. | RK73H1ETTP1622F | 24 | G | R318,R326,R406,R422,R438,R455,R470,R487,R612,R629,R644,R661,R676,R693,R708,R725,R740,R757,R772,R789,R804,R821,R836,R853 |  |  |  |  |  |  |
|  |  |  |  |  | 68 | 610115Y00-011-G |  | RES,16.2KOhm,+/-1%,1/16W,G,SMD0402 | YAGEO CORPORATION COMPONENT | RC0402FR-0716K2L |  | G |  |  |  |  |  |  |  |
|  |  |  |  |  | 68 | 610115Y00-012-G |  | RES,16.2KOhm,+/-1%,1/16W,G,SMD0402 | WALSIN TECHNOLOGY CORPORATION | WR04X1622FTL |  | G |  |  |  |  |  |  |  |
|  |  |  |  |  | 68 | 610115Y00-044-G |  | RES,16.2KOhm,+/-1%,1/16W,G,SMD0402 | TA-I TECHNOLOGY CO., LTD | RM04FTN1622 |  | G |  |  |  |  |  |  |  |
|  |  |  |  |  | 68 | 610115Y00-024-G |  | RES,16.2KOhm,+/-1%,1/16W,G,SMD0402 | PANASONIC INDUSTRIAL CO.,LTD. | ERJ2RKF1622X |  | G |  |  |  |  |  |  |  |
|  |  |  |  |  | 68 | 610115Y00-029-G |  | RES,16.2KOhm,+/-1%,1/16W,G,SMD0402 | VISHAY ENTER TECHNO LOGY.INC | CRCW040216K2FKED |  | G |  |  |  |  |  |  |  |
|  |  |  |  | 69 | 69 | 61100LQ00-017-G |  | RES,20KOhm,+/-1%,1/16W,G,SMD0402 | KOA SPEER ELECTRONICS, INC. | RN731ETTP2002F50 | 44 | G | R348,R1522,R1523,R1524,R1525,R1526,R1527,R1528,R1529,R1530,R1531,R1532,R1533,R1534,R1535,R1536,R1537,R1538,R1539,R1540,R1541,R1542,R1543,R1544,R1545,R1546,R1547,R1548,R1549,R1550,R1551,R1552,R1553,R1554,R1555,R1556,R1557,R1558,R1559,R1560,R1561,R1563,R1565,R1567 |  |  |  |  |  |  |
|  |  |  |  |  | 69 | 61100LQ00-011-G |  | RES,20KOhm,+/-1%,1/16W,G,SMD0402 | YAGEO CORPORATION COMPONENT | RT0402FRE0720KL |  | G |  |  |  |  |  |  |  |
|  |  |  |  |  | 69 | 61100LQ00-044-G |  | RES,20KOhm,+/-1%,1/16W,G,SMD0402 | TA-I TECHNOLOGY CO., LTD | RB04FTS2002 |  | G |  |  |  |  |  |  |  |
|  |  |  |  |  | 69 | 61100LQ00-012-G |  | RES,20KOhm,+/-1%,1/16W,G,SMD0402 | WALSIN TECHNOLOGY CORPORATION | WF04T2002FTL |  | G |  |  |  |  |  |  |  |
|  |  |  |  | 70 | 70 | 610114J00-017-G | - | RES,2KOhm,+/-1%,1/16W,G,SMD0402 | KOA SPEER ELECTRONICS, INC. | RK73H1ETTP2001F | 5 | G | R501,R502,R508,R544,R545 |  |  |  |  |  |  |
|  |  |  |  |  | 70 | 610114J00-012-G |  | RES,2KOhm,+/-1%,1/16W,G,SMD0402 | WALSIN TECHNOLOGY CORPORATION | WR04X2001FTL |  | G |  |  |  |  |  |  |  |
|  |  |  |  |  | 70 | 610114J00-011-G |  | RES,2KOhm,+/-1%,1/16W,G,SMD0402 | YAGEO CORPORATION COMPONENT | RC0402FR-072KL |  | G |  |  |  |  |  |  |  |
|  |  |  |  |  | 70 | 610114J00-044-G |  | RES,2KOhm,+/-1%,1/16W,G,SMD0402 | TA-I TECHNOLOGY CO., LTD | RM04FTN2001 |  | G |  |  |  |  |  |  |  |
|  |  |  |  |  | 70 | 610114J00-024-G |  | RES,2KOhm,+/-1%,1/16W,G,SMD0402 | PANASONIC INDUSTRIAL CO.,LTD. | ERJ2RKF2001X |  | G |  |  |  |  |  |  |  |
|  |  |  |  |  | 70 | 610114J00-029-G |  | RES,2KOhm,+/-1%,1/16W,G,SMD0402 | VISHAY ENTER TECHNO LOGY.INC | CRCW04022K00FKED |  | G |  |  |  |  |  |  |  |
|  |  |  |  | 71 | 71 | 610100T00-017-G |  | RES,1KOhm,+/-5%,1/16W,G,SMD0402 | KOA SPEER ELECTRONICS, INC. | RK73B1ETTP102J | 41 | G | R515,R517,R518,R519,R521,R522,R523,R524,R558,R561,R562,R564,R565,R566,R567,R1314,R1786,R1789,R1790,R1792,R1794,R1797,R1798,R1801,R1802,R1805,R1806,R1809,R1810,R1813,R1814,R1817,R1818,R1821,R1822,R1825,R1826,R1829,R1830,R2052,R2082 |  |  |  |  |  |  |
|  |  |  |  |  | 71 | 610100T00-012-G |  | RES,1KOhm,+/-5%,1/16W,G,SMD0402 | WALSIN TECHNOLOGY CORPORATION | WR04X102JTL |  | G |  |  |  |  |  |  |  |
|  |  |  |  |  | 71 | 610100T00-011-G |  | RES,1KOhm,+/-5%,1/16W,G,SMD0402 | YAGEO CORPORATION COMPONENT | RC0402JR-071KL |  | G |  |  |  |  |  |  |  |
|  |  |  |  |  | 71 | 610100T00-044-G |  | RES,1KOhm,+/-5%,1/16W,G,SMD0402 | TA-I TECHNOLOGY CO., LTD | RM04JTN102 |  | G |  |  |  |  |  |  |  |
|  |  |  |  |  | 71 | 610100T00-024-G |  | RES,1KOhm,+/-5%,1/16W,G,SMD0402 | PANASONIC INDUSTRIAL CO.,LTD. | ERJ2GEJ102X |  | G |  |  |  |  |  |  |  |
|  |  |  |  | 72 | 72 | 61010L300-017-G | - | RES,1KOhm,+/-1%,1/16W,G,SMD0402 | KOA SPEER ELECTRONICS, INC. | RK73H1ETTP1001F | 10 | G | R525,R532,R865,R1072,R1073,R1074,R1077,R1438,R1439,R1440 |  |  |  |  |  |  |
|  |  |  |  |  | 72 | 61010L300-012-G |  | RES,1KOhm,+/-1%,1/16W,G,SMD0402 | WALSIN TECHNOLOGY CORPORATION | WR04X1001FTL |  | G |  |  |  |  |  |  |  |
|  |  |  |  |  | 72 | 61010L300-011-G |  | RES,1KOhm,+/-1%,1/16W,G,SMD0402 | YAGEO CORPORATION COMPONENT | RC0402FR-071KL |  | G |  |  |  |  |  |  |  |
|  |  |  |  |  | 72 | 61010L300-044-G |  | RES,1KOhm,+/-1%,1/16W,G,SMD0402 | TA-I TECHNOLOGY CO., LTD | RM04FTN1001 |  | G |  |  |  |  |  |  |  |
|  |  |  |  |  | 72 | 61010L300-024-G |  | RES,1KOhm,+/-1%,1/16W,G,SMD0402 | PANASONIC INDUSTRIAL CO.,LTD. | ERJ2RKF1001X |  | G |  |  |  |  |  |  |  |
|  |  |  |  |  | 72 | 61010L300-029-G |  | RES,1KOhm,+/-1%,1/16W,G,SMD0402 | VISHAY ENTER TECHNO LOGY.INC | CRCW04021K00FKED |  | G |  |  |  |  |  |  |  |
|  |  |  |  | 73 | 73 | 61010PS00-017-G | - | RES,200KOhm,+/-1%,1/16W,G,SMD0402 | KOA SPEER ELECTRONICS, INC. | RK73H1ETTP2003F | 2 | G | R526,R533 |  |  |  |  |  |  |
|  |  |  |  |  | 73 | 61010PS00-012-G |  | RES,200KOhm,+/-1%,1/16W,G,SMD0402 | WALSIN TECHNOLOGY CORPORATION | WR04X2003FTL |  | G |  |  |  |  |  |  |  |
|  |  |  |  |  | 73 | 61010PS00-011-G |  | RES,200KOhm,+/-1%,1/16W,G,SMD0402 | YAGEO CORPORATION COMPONENT | RC0402FR-07200KL |  | G |  |  |  |  |  |  |  |
|  |  |  |  |  | 73 | 61010PS00-044-G |  | RES,200KOhm,+/-1%,1/16W,G,SMD0402 | TA-I TECHNOLOGY CO., LTD | RM04FTN2003 |  | G |  |  |  |  |  |  |  |
|  |  |  |  | 74 | 74 | 61011BW00-017-G |  | RES,1.2KOhm,+/-1%,1/16W,G,SMD0402 | KOA SPEER ELECTRONICS, INC. | RK73H1ETTP1201F | 2 | G | R529,R535 |  |  |  |  |  |  |
|  |  |  |  |  | 74 | 61011BW00-012-G |  | RES,1.2KOhm,+/-1%,1/16W,G,SMD0402 | WALSIN TECHNOLOGY CORPORATION | WR04X1201FTL |  | G |  |  |  |  |  |  |  |
|  |  |  |  |  | 74 | 61011BW00-011-G |  | RES,1.2KOhm,+/-1%,1/16W,G,SMD0402 | YAGEO CORPORATION COMPONENT | RC0402FR-071K2L |  | G |  |  |  |  |  |  |  |
|  |  |  |  |  | 74 | 61011BW00-044-G |  | RES,1.2KOhm,+/-1%,1/16W,G,SMD0402 | TA-I TECHNOLOGY CO., LTD | RM04FTN1201 |  | G |  |  |  |  |  |  |  |
|  |  |  |  | 75 | 75 | 610116V00-017-G | - | RES,232KOhm,+/-1%,1/16W,G,SMD0402 | KOA SPEER ELECTRONICS, INC. | RK73H1ETTP2323F | 1 | G | R530 |  |  |  |  |  |  |
|  |  |  |  |  | 75 | 610116V00-012-G |  | RES,232KOhm,+/-1%,1/16W,G,SMD0402 | WALSIN TECHNOLOGY CORPORATION | WR04X2323FTL |  | G |  |  |  |  |  |  |  |
|  |  |  |  |  | 75 | 610116V00-011-G |  | RES,232KOhm,+/-1%,1/16W,G,SMD0402 | YAGEO CORPORATION COMPONENT | RC0402FR-07232KL |  | G |  |  |  |  |  |  |  |
|  |  |  |  |  | 75 | 610116V00-044-G |  | RES,232KOhm,+/-1%,1/16W,G,SMD0402 | TA-I TECHNOLOGY CO., LTD | RM04FTN2323 |  | G |  |  |  |  |  |  |  |
|  |  |  |  | 76 | 76 | 610116B00-017-G |  | RES,180KOhm,+/-1%,1/16W,G,SMD0402 | KOA SPEER ELECTRONICS, INC. | RK73H1ETTP1803F | 1 | G | R534 |  |  |  |  |  |  |
|  |  |  |  |  | 76 | 610116B00-012-G |  | RES,180KOhm,+/-1%,1/16W,G,SMD0402 | WALSIN TECHNOLOGY CORPORATION | WR04X1803FTL |  | G |  |  |  |  |  |  |  |
|  |  |  |  |  | 76 | 610116B00-011-G |  | RES,180KOhm,+/-1%,1/16W,G,SMD0402 | YAGEO CORPORATION COMPONENT | RC0402FR-07180KL |  | G |  |  |  |  |  |  |  |
|  |  |  |  |  | 76 | 610116B00-044-G |  | RES,180KOhm,+/-1%,1/16W,G,SMD0402 | TA-I TECHNOLOGY CO., LTD | RM04FTN1803 |  | G |  |  |  |  |  |  |  |
|  |  |  |  | 77 | 77 | 61011BQ00-017-G | - | RES,2.2 Ohm,+/-5%,1/16W,G,SMD0402 | KOA SPEER ELECTRONICS, INC. | RK73B1ETTP2R2J | 2 | G | R540,R583 |  |  |  |  |  |  |
|  |  |  |  |  | 77 | 61011BQ00-011-G |  | RES,2.2 Ohm,+/-5%,1/16W,G,SMD0402 | YAGEO CORPORATION COMPONENT | RC0402JR-072R2L |  | G |  |  |  |  |  |  |  |
|  |  |  |  |  | 77 | 61011BQ00-012-G |  | RES,2.2 Ohm,+/-5%,1/16W,G,SMD0402 | WALSIN TECHNOLOGY CORPORATION | WR04X2R2JTL |  | G |  |  |  |  |  |  |  |
|  |  |  |  |  | 77 | 61011BQ00-044-G |  | RES,2.2 Ohm,+/-5%,1/16W,G,SMD0402 | TA-I TECHNOLOGY CO., LTD | RM04JTN2R2 |  | G |  |  |  |  |  |  |  |
|  |  |  |  | 78 | 78 | 610108300-017-G | - | RES,0 Ohm,+/-5%,1/10W,G,SMD0603 | KOA SPEER ELECTRONICS, INC. | RK73Z1JTTD | 2 | G | R542,R585 |  |  |  |  |  |  |
|  |  |  |  |  | 78 | 610108300-012-G |  | RES,0 Ohm,+/-5%,1/10W,G,SMD0603 | WALSIN TECHNOLOGY CORPORATION | WR06X000PTL |  | G |  |  |  |  |  |  |  |
|  |  |  |  |  | 78 | 610108300-011-G |  | RES,0 Ohm,+/-5%,1/10W,G,SMD0603 | YAGEO CORPORATION COMPONENT | RC0603JR-070RL |  | G |  |  |  |  |  |  |  |
|  |  |  |  |  | 78 | 610108300-044-G |  | RES,0 Ohm,+/-5%,1/10W,G,SMD0603 | TA-I TECHNOLOGY CO., LTD | RM06JTN0 |  | G |  |  |  |  |  |  |  |
|  |  |  |  |  | 78 | 610108300-024-G |  | RES,0 Ohm,+/-5%,1/10W,G,SMD0603 | PANASONIC INDUSTRIAL CO.,LTD. | ERJ3GEY0R00V |  | G |  |  |  |  |  |  |  |
|  |  |  |  | 79 | 79 | 61010FE00-017-G | - | RES,100 Ohm,+/-1%,1/16W,G,SMD0402 | KOA SPEER ELECTRONICS, INC. | RK73H1ETTP1000F | 1 | G | R543 |  |  |  |  |  |  |
|  |  |  |  |  | 79 | 61010FE00-012-G |  | RES,100 Ohm,+/-1%,1/16W,G,SMD0402 | WALSIN TECHNOLOGY CORPORATION | WR04X1000FTL |  | G |  |  |  |  |  |  |  |
|  |  |  |  |  | 79 | 61010FE00-011-G |  | RES,100 Ohm,+/-1%,1/16W,G,SMD0402 | YAGEO CORPORATION COMPONENT | RC0402FR-07100RL |  | G |  |  |  |  |  |  |  |
|  |  |  |  |  | 79 | 61010FE00-044-G |  | RES,100 Ohm,+/-1%,1/16W,G,SMD0402 | TA-I TECHNOLOGY CO., LTD | RM04FTN1000 |  | G |  |  |  |  |  |  |  |
|  |  |  |  | 80 | 80 | 610118400-017-G |  | RES,27 Ohm,+/-1%,1/16W,G,SMD0402 | KOA SPEER ELECTRONICS, INC. | RK73H1ETTP27R0F | 32 | G | R817,R818,R828,R830,R832,R833,R834,R860,R867,R1443,R1444,R1445,R1446,R1447,R1448,R1458,R1459,R1460,R1461,R1462,R1463,R1464,R1465,R1466,R1467,R1468,R1469,R1470,R1471,R1472,R1473,R1604 |  |  |  |  |  |  |
|  |  |  |  |  | 80 | 610118400-012-G |  | RES,27 Ohm,+/-1%,1/16W,G,SMD0402 | WALSIN TECHNOLOGY CORPORATION | WR04X27R0FTL |  | G |  |  |  |  |  |  |  |
|  |  |  |  |  | 80 | 610118400-011-G |  | RES,27 Ohm,+/-1%,1/16W,G,SMD0402 | YAGEO CORPORATION COMPONENT | RC0402FR-0727RL |  | G |  |  |  |  |  |  |  |
|  |  |  |  |  | 80 | 610118400-044-G |  | RES,27 Ohm,+/-1%,1/16W,G,SMD0402 | TA-I TECHNOLOGY CO., LTD | RM04FTN27R0 |  | G |  |  |  |  |  |  |  |
|  |  |  |  | 81 | 81 | 610113A00-017-G | - | RES,2.2 Ohm,+/-5%,1/2W,G,SMD1210 | KOA SPEER ELECTRONICS, INC. | RK73B2ETTD2R2J | 24 | G | R874,R876,R878,R880,R882,R884,R886,R888,R890,R892,R894,R896,R898,R900,R902,R904,R906,R908,R910,R912,R914,R916,R918,R920 |  |  |  |  |  |  |
|  |  |  |  |  | 81 | 610113A00-012-G |  | RES,2.2 Ohm,+/-5%,1/2W,G,SMD1210 | WALSIN TECHNOLOGY CORPORATION | WF10P2R2JTL |  | G |  |  |  |  |  |  |  |
|  |  |  |  |  | 81 | 610113A00-011-G |  | RES,2.2 Ohm,+/-5%,1/2W,G,SMD1210 | YAGEO CORPORATION COMPONENT | RC1210JR-072R2L |  | G |  |  |  |  |  |  |  |
|  |  |  |  | 82 | 82 | 61015K700-017-G |  | RES,3.3 Ohm,+/-5%,1/2W,G,SMD1210 | KOA SPEER ELECTRONICS, INC. | RK73B2ETTD3R3J | 24 | G | R875,R877,R879,R881,R883,R885,R887,R889,R891,R893,R895,R897,R899,R901,R903,R905,R907,R909,R911,R913,R915,R917,R919,R921 |  |  |  |  |  |  |
|  |  |  |  |  | 82 | 61015K700-011-G |  | RES,3.3 Ohm,+/-5%,1/2W,G,SMD1210 | YAGEO CORPORATION COMPONENT | RC1210JR-073R3L |  | G |  |  |  |  |  |  |  |
|  |  |  |  | 83 | 83 | 61011MV00-017-G |  | RES,510 Ohm,+/-1%,1/16W,G,SMD0402 | KOA SPEER ELECTRONICS, INC. | RK73H1ETTP5100F | 24 | G | R1313,R1785,R1787,R1788,R1791,R1793,R1795,R1796,R1799,R1800,R1803,R1804,R1807,R1808,R1811,R1812,R1815,R1816,R1819,R1820,R1823,R1824,R1827,R1828 |  |  |  |  |  |  |
|  |  |  |  |  | 83 | 61011MV00-012-G |  | RES,510 Ohm,+/-1%,1/16W,G,SMD0402 | WALSIN TECHNOLOGY CORPORATION | WR04X5100FTL |  | G |  |  |  |  |  |  |  |
|  |  |  |  |  | 83 | 61011MV00-011-G |  | RES,510 Ohm,+/-1%,1/16W,G,SMD0402 | YAGEO CORPORATION COMPONENT | RC0402FR-07510RL |  | G |  |  |  |  |  |  |  |
|  |  |  |  |  | 83 | 61011MV00-044-G |  | RES,510 Ohm,+/-1%,1/16W,G,SMD0402 | TA-I TECHNOLOGY CO., LTD | RM04FTN5100 |  | G |  |  |  |  |  |  |  |
|  |  |  |  | 84 | 84 | 610107L00-017-G |  | RES,1 Ohm,+/-5%,1/10W,G,SMD0603 | KOA SPEER ELECTRONICS, INC. | RK73B1JTTD1R0J | 2 | G | R1408,R1449 |  |  |  |  |  |  |
|  |  |  |  |  | 84 | 610107L00-011-G |  | RES,1 Ohm,+/-5%,1/10W,G,SMD0603 | YAGEO CORPORATION COMPONENT | RC0603JR-071RL |  | G |  |  |  |  |  |  |  |
|  |  |  |  |  | 84 | 610107L00-012-G |  | RES,1 Ohm,+/-5%,1/10W,G,SMD0603 | WALSIN TECHNOLOGY CORPORATION | WR06X1R0JTL |  | G |  |  |  |  |  |  |  |
|  |  |  |  |  | 84 | 610107L00-044-G |  | RES,1 Ohm,+/-5%,1/10W,G,SMD0603 | TA-I TECHNOLOGY CO., LTD | RM06JTN1R0 |  | G |  |  |  |  |  |  |  |
|  |  |  |  | 85 | 85 | 61100AH00-044-G |  | RES,10KOhm,+/-0.5%,1/16W,G,SMD0402 | TA-I TECHNOLOGY CO., LTD | RB04DTP1002 | 12 | G | R2049,R2050,R2051,R2062,R2063,R2064,R2071,R2075,R2077,R2079,R2083,R2084 |  |  |  |  |  |  |
|  |  |  |  | 86 | 86 | 610154800-017-G |  | RES,1 Ohm,+/-5%,1/8W,G,SMD0402 | KOA SPEER ELECTRONICS, INC. | SG73P1ETTP1R0J | 1 | G | R2060 |  |  |  |  |  |  |
|  |  |  |  |  | 86 | 610154800-011-G |  | RES,1 Ohm,+/-5%,1/8W,G,SMD0402 | YAGEO CORPORATION COMPONENT | RC0402JR-7W1RL |  | G |  |  |  |  |  |  |  |
|  |  |  |  |  | 86 | 610154800-012-G |  | RES,1 Ohm,+/-5%,1/8W,G,SMD0402 | WALSIN TECHNOLOGY CORPORATION | WF04P1R0 JTL |  | G |  |  |  |  |  |  |  |
|  |  |  |  | 87 | 87 | 310103J00-223-G |  | IC,Gate&Inverter,NL17SZ08DFT2G,1.65~5.5V,G,SOT353-5,SMD | ON SEMICONDUCTOR CORP | NL17SZ08DFT2G | 3 | G | U_AND1,U_AND2,U5 |  |  |  |  |  |  |
|  |  |  |  | 88 | 88 | 410401W00-214-G |  | EEPROM,M24C02-WMN6TP,2.5~5.5V,256*8,I2C,G,SOIC-8,SMD | ST MICRO ELECTRONICS,INC | M24C02-WMN6TP | 1 | G | U_BP_FRU1 |  |  |  |  |  |  |
|  |  |  |  | 89 | 89 | 21050LL00-217-G | - | IC,IDT,9ZXL0831AKLFT,G,VFQFPN-48,SMD | INTEGRATED DEVICE TECHNOLOGY | 9ZXL0831AKLFT | 2 | G | U_Clock_B,U_Clock_A |  |  |  |  |  |  |
|  |  |  |  | 90 | 90 | 311004800-031-G | - | IC,Translator,PCA9617ADPJ,0.8~5.5V,2.2~5.5V,G,TSSOP-8,SMD | NXP SEMICONDUCTORS | PCA9617ADPJ | 2 | G | U_I2C_RE1,U_I2C_RE2 |  |  |  |  |  |  |
|  |  |  |  | 91 | 91 | 31030CA00-031-G |  | IC,Switch,PCA9546APW,2.3~5.5V,G,TSSOP-16,SMD | NXP SEMICONDUCTORS | PCA9546APW | 5 | G | U_MUX1,U_MUX2,U_MUX3,U_MUX4,U_MUX5 |  |  |  |  |  |  |
|  |  |  |  | 92 | 92 | 32040P400-399-G |  | IC,Voltage sensor,SLG4N020VTR,G,TDFN-8,SMD | SILEGO | SLG4N020VTR | 1 | G | U_RESET |  |  |  |  |  |  |
|  |  |  |  | 93 | 93 | 32022WB00-173-G |  | IC,Power Controller,MAX6420UK16+T,G,SOT-23-5P,SMD | MAXIM INTEGRATED PRODUCTS, INC. | MAX6420UK16+T | 1 | G | U_RESET1 |  |  |  |  |  |  |
|  |  |  |  | 94 | 94 | 21081NC00-432-G |  | IC,LSI,500021009,A2,G,TFBGA-141,SMD | LSI LOGIC CORPORATION | 500021009 | 2 | G | U_SF1,U_SF2 |  |  |  |  |  |  |
|  |  |  |  | 95 | 95 | 32040PJ00-223-G |  | IC,Temperature Sensor,NCT75DMR2G,G,MSOP-8,SMD | ON SEMICONDUCTOR CORP | NCT75DMR2G | 1 | G | U_TMP1 |  |  |  |  |  |  |
|  |  |  |  | 96 | 96 | 311002900-031-G |  | IC,Translator,PCA9306DC1,1.0~3.6V,1.8~5.5V,G,VSSOP-8,SMD | NXP SEMICONDUCTORS | PCA9306DC1 | 2 | G | U1,U2 |  |  |  |  |  |  |
|  |  |  |  | 97 | 97 | 21050RJ00-217-G |  | IC,IDT,9FGL0651BKILFT,G,VFQFPN-40,SMD | INTEGRATED DEVICE TECHNOLOGY | 9FGL0651BKILFT | 1 | G | U29 |  |  |  |  |  |  |
|  |  |  |  | 98 | 98 | 310501200-183-G | - | IC,Buffer,SN74LVC1G07DCKR,1.65~5.5V,G,SC70-5,SMD | TEXAS INSTRUMENTS | SN74LVC1G07DCKR | 1 | G | U209 |  |  |  |  |  |  |
|  |  |  |  | 99 | 99 | 220106A00-413-G |  | IC,PLD,10M08SCU169C8G,3.3V,116MHz,G,BGA-169,SMD | ALTERA CORPORATION | 10M08SCU169C8G | 1 | G | U248 |  |  |  |  |  |  |
|  |  |  |  | 100 | 100 | 71012HD00-100-G |  | XTAL,25MHz,+/-20ppm,8pF,G,SMD | TXC CORPORATION | 7V25000054 | 1 | G | X7 |  |  |  |  |  |  |
|  |  |  |  | 101 | 101 | 2A5910Q00-HYM-G |  | SMT NUT,CARBON STEEL,G,FIVETECH,82-059-01-022-01-RL | Fivetech Technology Inc. | 82-059-01-022-01-RL | 10 | G | H1,H2,H3,H4,H7,H8,H9,H10,H30,H31 |  |  |  |  |  |  |
|  |  |  |  | 102 | 102 | U10-B274-250T |  | CONN,SAS,V/T,0.6mm,30u,G,SMD-74 | AMPHENOL SHANGHAI CORP. | U10-B274-250T | 10 | G | JSAS1,JPCIE1,JSAS2,JPCIE2,JSAS3,JPCIE3,JPCIE4,JPCIE5,JPCIE6,JPCIE7 |  |  |  |  |  |  |
|  |  |  |  | 103 | 103 | 3406B6F00-317-G |  | CONN,Header,WTB,2X3,R/A,Bla,2.5mm,15u,G,SMD-6 | MOLEX INCORPORATED | 15-91-2065 | 1 | G | J_CPLD_JTAG |  |  |  |  |  |  |
|  |  |  |  | 104 | 104 | 34066NA00-32M-G |  | Header&Socket Connector,80012-0427,Wire-to-Board Header,4,SMD,THERMOPLASTIC,1mm,100u",Nature,G | BELLWETHER ELECTRONIC CORP. | 80012-0427 | 1 | G | J_LED1 |  |  |  |  |  |  |
|  |  |  |  | 105 | 105 | 34031BQ00-317-G |  | CONN,PCIE,V/T,Bla,0.8mm,30u,G,SMD-68 | MOLEX INCORPORATED | 78777-1002 | 24 | G | J_NVME01,J_NVME02,J_NVME03,J_NVME04,J_NVME05,J_NVME06,J_NVME07,J_NVME08,J_NVME09,J_NVME10,J_NVME11,J_NVME12,J_NVME13,J_NVME14,J_NVME15,J_NVME16,J_NVME17,J_NVME18,J_NVME19,J_NVME20,J_NVME21,J_NVME22,J_NVME23,J_NVME00 |  |  |  |  |  |  |
|  |  |  |  | 106 | 106 | 3406B3H00-317-G |  | CONN,Header,Power,2X8,V/T,Bla,3mm,G,SMD-16 | MOLEX INCORPORATED | 43045-1618 | 1 | G | J1 |  |  |  |  |  |  |
